(kicad_pcb
	(version 20260206)
	(generator "pcbnew")
	(generator_version "10.0")
	(general
		(thickness 1.6)
		(legacy_teardrops no)
	)
	(paper "A4")
	(title_block
		(title "pdpb — Lightning_PDPB_BRD.brd")
		(comment 1 "Lightning (Wiwynn / Facebook NVMe JBOF) / footprints 656-662 of 1140")
	)
	(layers
		(0 "F.Cu" signal "TOP")
		(4 "In1.Cu" signal "L2GND")
		(6 "In2.Cu" signal "L3")
		(8 "In3.Cu" signal "L4VCC")
		(10 "In4.Cu" signal "L5VCC")
		(12 "In5.Cu" signal "L6")
		(14 "In6.Cu" signal "L7GND")
		(2 "B.Cu" signal "BOTTOM")
		(9 "F.Adhes" user "F.Adhesive")
		(11 "B.Adhes" user "B.Adhesive")
		(13 "F.Paste" user "Package Geometry/Pastemask Top")
		(15 "B.Paste" user "Package Geometry/Pastemask Bottom")
		(5 "F.SilkS" user "Ref Des/Silkscreen Top")
		(7 "B.SilkS" user "Ref Des/Silkscreen Bottom")
		(1 "F.Mask" user "Board Geometry/Soldermask Top")
		(3 "B.Mask" user "Board Geometry/Soldermask Bottom")
		(17 "Dwgs.User" user "User.Drawings")
		(19 "Cmts.User" user "User.Comments")
		(21 "Eco1.User" user "User.Eco1")
		(23 "Eco2.User" user "User.Eco2")
		(25 "Edge.Cuts" user "Board Geometry/Outline")
		(27 "Margin" user)
		(31 "F.CrtYd" user "Package Geometry/Place Bound Top")
		(29 "B.CrtYd" user "Package Geometry/Place Bound Bottom")
		(35 "F.Fab" user "Ref Des/Assembly Top")
		(33 "B.Fab" user "Ref Des/Assembly Bottom")
	)
	(footprint ""
		(layer "F.Cu")
		(at 222.123 -348.103952)
		(property "Reference" "Q35"
			(at 0 0 0)
			(layer "F.SilkS")
			(hide yes)
			(effects
				(font
					(size 1.27 1.27)
				)
			)
		)
		(property "Value" "2N7002A-7-GP"
			(at 0.127 -8.9662 0)
			(unlocked yes)
			(layer "F.Fab")
			(hide yes)
			(effects
				(font
					(size 1.016 1.016)
					(thickness 0.1524)
				)
			)
		)
		(property "Device Type" "SOT23DGS2D4H48"
			(at 0.127 -10.4902 0)
			(unlocked yes)
			(layer "F.Fab")
			(hide yes)
			(effects
				(font
					(size 1.016 1.016)
					(thickness 0.1524)
				)
			)
		)
		(duplicate_pad_numbers_are_jumpers no)
		(fp_line
			(start -1.651 -1.778)
			(end -1.651 1.778)
			(stroke
				(width 0.1524)
				(type default)
			)
			(layer "F.SilkS")
		)
		(fp_line
			(start -1.651 1.778)
			(end 1.651 1.778)
			(stroke
				(width 0.1524)
				(type default)
			)
			(layer "F.SilkS")
		)
		(fp_line
			(start 1.651 -1.778)
			(end -1.651 -1.778)
			(stroke
				(width 0.1524)
				(type default)
			)
			(layer "F.SilkS")
		)
		(fp_line
			(start 1.651 1.778)
			(end 1.651 -1.778)
			(stroke
				(width 0.1524)
				(type default)
			)
			(layer "F.SilkS")
		)
		(fp_poly
			(pts
				(xy -1.778 1.8796) (xy -1.778 -1.8796) (xy 1.778 -1.8796) (xy 1.778 1.8796)
			)
			(stroke
				(width 0)
				(type default)
			)
			(fill no)
			(layer "F.CrtYd")
		)
		(fp_poly
			(pts
				(xy -1.778 1.8796) (xy -1.778 -1.8796) (xy 1.778 -1.8796) (xy 1.778 1.8796)
			)
			(stroke
				(width 0)
				(type default)
			)
			(fill no)
			(layer "F.Fab")
		)
		(pad "D" smd custom
			(at 0 -0.9525)
			(size 0.1905 0.1905)
			(layers "F.Cu" "F.Mask" "F.Paste")
			(net "ATTN_LED_DR1_MOS_N")
			(options
				(clearance outline)
				(anchor circle)
			)
			(primitives
				(gr_poly
					(pts
						(arc
							(start -0.1778 0.5715)
							(mid -0.321484 0.511984)
							(end -0.381 0.3683)
						)
						(arc
							(start -0.381 -0.3683)
							(mid -0.321484 -0.511984)
							(end -0.1778 -0.5715)
						)
						(arc
							(start 0.1778 -0.5715)
							(mid 0.321484 -0.511984)
							(end 0.381 -0.3683)
						)
						(arc
							(start 0.381 0.3683)
							(mid 0.321484 0.511984)
							(end 0.1778 0.5715)
						)
					)
					(width 0)
					(fill yes)
				)
			)
		)
		(pad "G" smd custom
			(at -0.98425 0.9525)
			(size 0.1905 0.1905)
			(layers "F.Cu" "F.Mask" "F.Paste")
			(net "SSD1_CLK0_OE_MOS_N")
			(options
				(clearance outline)
				(anchor circle)
			)
			(primitives
				(gr_poly
					(pts
						(arc
							(start -0.1778 0.5715)
							(mid -0.321484 0.511984)
							(end -0.381 0.3683)
						)
						(arc
							(start -0.381 -0.3683)
							(mid -0.321484 -0.511984)
							(end -0.1778 -0.5715)
						)
						(arc
							(start 0.1778 -0.5715)
							(mid 0.321484 -0.511984)
							(end 0.381 -0.3683)
						)
						(arc
							(start 0.381 0.3683)
							(mid 0.321484 0.511984)
							(end 0.1778 0.5715)
						)
					)
					(width 0)
					(fill yes)
				)
			)
		)
		(pad "S" smd custom
			(at 0.98425 0.9525)
			(size 0.1905 0.1905)
			(layers "F.Cu" "F.Mask" "F.Paste")
			(net "ATTN_LED_DR1_R")
			(options
				(clearance outline)
				(anchor circle)
			)
			(primitives
				(gr_poly
					(pts
						(arc
							(start -0.1778 0.5715)
							(mid -0.321484 0.511984)
							(end -0.381 0.3683)
						)
						(arc
							(start -0.381 -0.3683)
							(mid -0.321484 -0.511984)
							(end -0.1778 -0.5715)
						)
						(arc
							(start 0.1778 -0.5715)
							(mid 0.321484 -0.511984)
							(end 0.381 -0.3683)
						)
						(arc
							(start 0.381 0.3683)
							(mid 0.321484 0.511984)
							(end 0.1778 0.5715)
						)
					)
					(width 0)
					(fill yes)
				)
			)
		)
	)
	(footprint ""
		(layer "F.Cu")
		(at 96.52 -110.236 180)
		(property "Reference" "R9133"
			(at 0 0 180)
			(layer "F.SilkS")
			(hide yes)
			(effects
				(font
					(size 1.27 1.27)
				)
			)
		)
		(property "Value" "27R2F-GP"
			(at 0.064008 -3.993896 180)
			(unlocked yes)
			(layer "F.Fab")
			(hide yes)
			(effects
				(font
					(size 1.016 1.016)
					(thickness 0.1524)
				)
			)
		)
		(property "Device Type" "R402H16"
			(at 0.064008 -5.517896 180)
			(unlocked yes)
			(layer "F.Fab")
			(hide yes)
			(effects
				(font
					(size 1.016 1.016)
					(thickness 0.1524)
				)
			)
		)
		(duplicate_pad_numbers_are_jumpers no)
		(fp_line
			(start 0.508 -0.9398)
			(end -0.508 -0.9398)
			(stroke
				(width 0.1524)
				(type default)
			)
			(layer "F.SilkS")
		)
		(fp_line
			(start -0.508 -0.9398)
			(end -0.508 0.9398)
			(stroke
				(width 0.1524)
				(type default)
			)
			(layer "F.SilkS")
		)
		(fp_rect
			(start -0.508 0.9398)
			(end 0.508 -0.9398)
			(stroke
				(width 0)
				(type default)
			)
			(fill no)
			(layer "F.CrtYd")
		)
		(fp_rect
			(start -0.508 0.9398)
			(end 0.508 -0.9398)
			(stroke
				(width 0)
				(type default)
			)
			(fill no)
			(layer "F.Fab")
		)
		(pad "1" smd custom
			(at 0 -0.4445 180)
			(size 0.1397 0.1397)
			(layers "F.Cu" "F.Mask" "F.Paste")
			(net "PE_CLK_100M_DR8_1_R_P")
			(options
				(clearance outline)
				(anchor circle)
			)
			(primitives
				(gr_poly
					(pts
						(arc
							(start -0.1778 -0.2794)
							(mid -0.249642 -0.249642)
							(end -0.2794 -0.1778)
						)
						(arc
							(start -0.2794 0.1778)
							(mid -0.249642 0.249642)
							(end -0.1778 0.2794)
						)
						(arc
							(start 0.1778 0.2794)
							(mid 0.249642 0.249642)
							(end 0.2794 0.1778)
						)
						(arc
							(start 0.2794 -0.1778)
							(mid 0.249642 -0.249642)
							(end 0.1778 -0.2794)
						)
					)
					(width 0)
					(fill yes)
				)
			)
		)
		(pad "2" smd custom
			(at 0 0.4445 180)
			(size 0.1397 0.1397)
			(layers "F.Cu" "F.Mask" "F.Paste")
			(net "PE_CLK100M_DR8_1_P")
			(options
				(clearance outline)
				(anchor circle)
			)
			(primitives
				(gr_poly
					(pts
						(arc
							(start -0.1778 -0.2794)
							(mid -0.249642 -0.249642)
							(end -0.2794 -0.1778)
						)
						(arc
							(start -0.2794 0.1778)
							(mid -0.249642 0.249642)
							(end -0.1778 0.2794)
						)
						(arc
							(start 0.1778 0.2794)
							(mid 0.249642 0.249642)
							(end 0.2794 0.1778)
						)
						(arc
							(start 0.2794 -0.1778)
							(mid 0.249642 -0.249642)
							(end 0.1778 -0.2794)
						)
					)
					(width 0)
					(fill yes)
				)
			)
		)
	)
	(footprint ""
		(layer "F.Cu")
		(at 89.535 -31.877 180)
		(property "Reference" "R382"
			(at 0 0 180)
			(layer "F.SilkS")
			(hide yes)
			(effects
				(font
					(size 1.27 1.27)
				)
			)
		)
		(property "Value" "0R2J-2-GP"
			(at 0.064008 -3.993896 180)
			(unlocked yes)
			(layer "F.Fab")
			(hide yes)
			(effects
				(font
					(size 1.016 1.016)
					(thickness 0.1524)
				)
			)
		)
		(property "Device Type" "R402H16"
			(at 0.064008 -5.517896 180)
			(unlocked yes)
			(layer "F.Fab")
			(hide yes)
			(effects
				(font
					(size 1.016 1.016)
					(thickness 0.1524)
				)
			)
		)
		(duplicate_pad_numbers_are_jumpers no)
		(fp_line
			(start 0.508 -0.9398)
			(end -0.508 -0.9398)
			(stroke
				(width 0.1524)
				(type default)
			)
			(layer "F.SilkS")
		)
		(fp_line
			(start -0.508 -0.9398)
			(end -0.508 0.9398)
			(stroke
				(width 0.1524)
				(type default)
			)
			(layer "F.SilkS")
		)
		(fp_rect
			(start -0.508 0.9398)
			(end 0.508 -0.9398)
			(stroke
				(width 0)
				(type default)
			)
			(fill no)
			(layer "F.CrtYd")
		)
		(fp_rect
			(start -0.508 0.9398)
			(end 0.508 -0.9398)
			(stroke
				(width 0)
				(type default)
			)
			(fill no)
			(layer "F.Fab")
		)
		(pad "1" smd custom
			(at 0 -0.4445 180)
			(size 0.1397 0.1397)
			(layers "F.Cu" "F.Mask" "F.Paste")
			(net "VOL_SEN_SDA")
			(options
				(clearance outline)
				(anchor circle)
			)
			(primitives
				(gr_poly
					(pts
						(arc
							(start -0.1778 -0.2794)
							(mid -0.249642 -0.249642)
							(end -0.2794 -0.1778)
						)
						(arc
							(start -0.2794 0.1778)
							(mid -0.249642 0.249642)
							(end -0.1778 0.2794)
						)
						(arc
							(start 0.1778 0.2794)
							(mid 0.249642 0.249642)
							(end 0.2794 0.1778)
						)
						(arc
							(start 0.2794 -0.1778)
							(mid 0.249642 -0.249642)
							(end 0.1778 -0.2794)
						)
					)
					(width 0)
					(fill yes)
				)
			)
		)
		(pad "2" smd custom
			(at 0 0.4445 180)
			(size 0.1397 0.1397)
			(layers "F.Cu" "F.Mask" "F.Paste")
			(net "I2C_B_SDA")
			(options
				(clearance outline)
				(anchor circle)
			)
			(primitives
				(gr_poly
					(pts
						(arc
							(start -0.1778 -0.2794)
							(mid -0.249642 -0.249642)
							(end -0.2794 -0.1778)
						)
						(arc
							(start -0.2794 0.1778)
							(mid -0.249642 0.249642)
							(end -0.1778 0.2794)
						)
						(arc
							(start 0.1778 0.2794)
							(mid 0.249642 0.249642)
							(end 0.2794 0.1778)
						)
						(arc
							(start 0.2794 -0.1778)
							(mid 0.249642 -0.249642)
							(end 0.1778 -0.2794)
						)
					)
					(width 0)
					(fill yes)
				)
			)
		)
	)
	(footprint ""
		(layer "F.Cu")
		(at 55.2958 -450.1134 -90)
		(property "Reference" "R9816"
			(at 0 0 270)
			(layer "F.SilkS")
			(hide yes)
			(effects
				(font
					(size 1.27 1.27)
				)
			)
		)
		(property "Value" "0R2J-2-GP"
			(at 0.064008 -3.993896 270)
			(unlocked yes)
			(layer "F.Fab")
			(hide yes)
			(effects
				(font
					(size 1.016 1.016)
					(thickness 0.1524)
				)
			)
		)
		(property "Device Type" "R402H16"
			(at 0.064008 -5.517896 270)
			(unlocked yes)
			(layer "F.Fab")
			(hide yes)
			(effects
				(font
					(size 1.016 1.016)
					(thickness 0.1524)
				)
			)
		)
		(duplicate_pad_numbers_are_jumpers no)
		(fp_line
			(start -0.508 -0.9398)
			(end -0.508 0.9398)
			(stroke
				(width 0.1524)
				(type default)
			)
			(layer "F.SilkS")
		)
		(fp_line
			(start 0.508 -0.9398)
			(end -0.508 -0.9398)
			(stroke
				(width 0.1524)
				(type default)
			)
			(layer "F.SilkS")
		)
		(fp_rect
			(start -0.508 0.9398)
			(end 0.508 -0.9398)
			(stroke
				(width 0)
				(type default)
			)
			(fill no)
			(layer "F.CrtYd")
		)
		(fp_rect
			(start -0.508 0.9398)
			(end 0.508 -0.9398)
			(stroke
				(width 0)
				(type default)
			)
			(fill no)
			(layer "F.Fab")
		)
		(pad "1" smd custom
			(at 0 -0.4445 270)
			(size 0.1397 0.1397)
			(layers "F.Cu" "F.Mask" "F.Paste")
			(net "ATTN_LED_DR5_R")
			(options
				(clearance outline)
				(anchor circle)
			)
			(primitives
				(gr_poly
					(pts
						(arc
							(start -0.1778 -0.2794)
							(mid -0.249642 -0.249642)
							(end -0.2794 -0.1778)
						)
						(arc
							(start -0.2794 0.1778)
							(mid -0.249642 0.249642)
							(end -0.1778 0.2794)
						)
						(arc
							(start 0.1778 0.2794)
							(mid 0.249642 0.249642)
							(end 0.2794 0.1778)
						)
						(arc
							(start 0.2794 -0.1778)
							(mid 0.249642 -0.249642)
							(end 0.1778 -0.2794)
						)
					)
					(width 0)
					(fill yes)
				)
			)
		)
		(pad "2" smd custom
			(at 0 0.4445 270)
			(size 0.1397 0.1397)
			(layers "F.Cu" "F.Mask" "F.Paste")
			(net "ATTN_LED_DR5_N")
			(options
				(clearance outline)
				(anchor circle)
			)
			(primitives
				(gr_poly
					(pts
						(arc
							(start -0.1778 -0.2794)
							(mid -0.249642 -0.249642)
							(end -0.2794 -0.1778)
						)
						(arc
							(start -0.2794 0.1778)
							(mid -0.249642 0.249642)
							(end -0.1778 0.2794)
						)
						(arc
							(start 0.1778 0.2794)
							(mid 0.249642 0.249642)
							(end 0.2794 0.1778)
						)
						(arc
							(start 0.2794 -0.1778)
							(mid 0.249642 -0.249642)
							(end 0.1778 -0.2794)
						)
					)
					(width 0)
					(fill yes)
				)
			)
		)
	)
	(footprint ""
		(layer "F.Cu")
		(at 99.187 -318.643)
		(property "Reference" "R9600"
			(at 0 0 0)
			(layer "F.SilkS")
			(hide yes)
			(effects
				(font
					(size 1.27 1.27)
				)
			)
		)
		(property "Value" "10R2F-L-GP"
			(at 0.064008 -3.993896 0)
			(unlocked yes)
			(layer "F.Fab")
			(hide yes)
			(effects
				(font
					(size 1.016 1.016)
					(thickness 0.1524)
				)
			)
		)
		(property "Device Type" "R402H14"
			(at 0.064008 -5.517896 0)
			(unlocked yes)
			(layer "F.Fab")
			(hide yes)
			(effects
				(font
					(size 1.016 1.016)
					(thickness 0.1524)
				)
			)
		)
		(duplicate_pad_numbers_are_jumpers no)
		(fp_line
			(start -0.508 -0.9398)
			(end -0.508 0.9398)
			(stroke
				(width 0.1524)
				(type default)
			)
			(layer "F.SilkS")
		)
		(fp_line
			(start 0.508 -0.9398)
			(end -0.508 -0.9398)
			(stroke
				(width 0.1524)
				(type default)
			)
			(layer "F.SilkS")
		)
		(fp_rect
			(start -0.508 0.9398)
			(end 0.508 -0.9398)
			(stroke
				(width 0)
				(type default)
			)
			(fill no)
			(layer "F.CrtYd")
		)
		(fp_rect
			(start -0.508 0.9398)
			(end 0.508 -0.9398)
			(stroke
				(width 0)
				(type default)
			)
			(fill no)
			(layer "F.Fab")
		)
		(pad "1" smd custom
			(at 0 -0.4445)
			(size 0.1397 0.1397)
			(layers "F.Cu" "F.Mask" "F.Paste")
			(net "SSD_PRSNT_NET6")
			(options
				(clearance outline)
				(anchor circle)
			)
			(primitives
				(gr_poly
					(pts
						(arc
							(start -0.1778 -0.2794)
							(mid -0.249642 -0.249642)
							(end -0.2794 -0.1778)
						)
						(arc
							(start -0.2794 0.1778)
							(mid -0.249642 0.249642)
							(end -0.1778 0.2794)
						)
						(arc
							(start 0.1778 0.2794)
							(mid 0.249642 0.249642)
							(end 0.2794 0.1778)
						)
						(arc
							(start 0.2794 -0.1778)
							(mid 0.249642 -0.249642)
							(end 0.1778 -0.2794)
						)
					)
					(width 0)
					(fill yes)
				)
			)
		)
		(pad "2" smd custom
			(at 0 0.4445)
			(size 0.1397 0.1397)
			(layers "F.Cu" "F.Mask" "F.Paste")
			(net "SSD_PRSNT6")
			(options
				(clearance outline)
				(anchor circle)
			)
			(primitives
				(gr_poly
					(pts
						(arc
							(start -0.1778 -0.2794)
							(mid -0.249642 -0.249642)
							(end -0.2794 -0.1778)
						)
						(arc
							(start -0.2794 0.1778)
							(mid -0.249642 0.249642)
							(end -0.1778 0.2794)
						)
						(arc
							(start 0.1778 0.2794)
							(mid 0.249642 0.249642)
							(end 0.2794 0.1778)
						)
						(arc
							(start 0.2794 -0.1778)
							(mid 0.249642 -0.249642)
							(end 0.1778 -0.2794)
						)
					)
					(width 0)
					(fill yes)
				)
			)
		)
	)
	(footprint ""
		(layer "F.Cu")
		(at 217.805 -436.88 -90)
		(property "Reference" "PL2"
			(at 0 0 270)
			(layer "F.SilkS")
			(hide yes)
			(effects
				(font
					(size 1.27 1.27)
				)
			)
		)
		(property "Value" "COIL-6D8UH-10-GP"
			(at -4.699 -4.0132 270)
			(unlocked yes)
			(layer "F.Fab")
			(hide yes)
			(effects
				(font
					(size 1.016 1.016)
					(thickness 0.1524)
				)
			)
		)
		(property "Device Type" "L7066-1830-UH119"
			(at -4.699 -5.5372 270)
			(unlocked yes)
			(layer "F.Fab")
			(hide yes)
			(effects
				(font
					(size 1.016 1.016)
					(thickness 0.1524)
				)
			)
		)
		(duplicate_pad_numbers_are_jumpers no)
		(fp_line
			(start -3.556 4.4958)
			(end -3.556 -4.4958)
			(stroke
				(width 0.1524)
				(type default)
			)
			(layer "F.SilkS")
		)
		(fp_line
			(start 3.556 4.4958)
			(end -3.556 4.4958)
			(stroke
				(width 0.1524)
				(type default)
			)
			(layer "F.SilkS")
		)
		(fp_line
			(start -3.556 -4.4958)
			(end 3.556 -4.4958)
			(stroke
				(width 0.1524)
				(type default)
			)
			(layer "F.SilkS")
		)
		(fp_line
			(start 3.556 -4.4958)
			(end 3.556 4.4958)
			(stroke
				(width 0.1524)
				(type default)
			)
			(layer "F.SilkS")
		)
		(fp_rect
			(start -3.302 3.4798)
			(end 3.302 -3.4798)
			(stroke
				(width 0)
				(type default)
			)
			(fill no)
			(layer "F.CrtYd")
		)
		(fp_poly
			(pts
				(xy -3.81 4.572) (xy -3.81 -4.572) (xy 3.81 -4.572) (xy 3.81 -0.5588) (xy 3.302 -0.5588) (xy 3.302 -3.4798)
				(xy -3.302 -3.4798) (xy -3.302 3.4798) (xy 3.302 3.4798) (xy 3.302 -0.5461) (xy 3.81 -0.5461) (xy 3.81 4.572)
			)
			(stroke
				(width 0)
				(type default)
			)
			(fill no)
			(layer "F.CrtYd")
		)
		(fp_rect
			(start -3.81 4.572)
			(end 3.81 -4.572)
			(stroke
				(width 0)
				(type default)
			)
			(fill no)
			(layer "F.Fab")
		)
		(pad "1" smd rect
			(at 0 -2.779522 270)
			(size 3.5052 2.921)
			(layers "F.Cu" "F.Mask" "F.Paste")
			(net "P3V3_SW")
		)
		(pad "2" smd rect
			(at 0 2.779522 270)
			(size 3.5052 2.921)
			(layers "F.Cu" "F.Mask" "F.Paste")
			(net "P3V3_OUT")
		)
	)
	(footprint ""
		(layer "F.Cu")
		(at 72.898 -354.965 180)
		(property "Reference" "R429"
			(at 0 0 180)
			(layer "F.SilkS")
			(hide yes)
			(effects
				(font
					(size 1.27 1.27)
				)
			)
		)
		(property "Value" "0R2J-2-GP"
			(at 0.064008 -3.993896 180)
			(unlocked yes)
			(layer "F.Fab")
			(hide yes)
			(effects
				(font
					(size 1.016 1.016)
					(thickness 0.1524)
				)
			)
		)
		(property "Device Type" "R402H16"
			(at 0.064008 -5.517896 180)
			(unlocked yes)
			(layer "F.Fab")
			(hide yes)
			(effects
				(font
					(size 1.016 1.016)
					(thickness 0.1524)
				)
			)
		)
		(duplicate_pad_numbers_are_jumpers no)
		(fp_line
			(start 0.508 -0.9398)
			(end -0.508 -0.9398)
			(stroke
				(width 0.1524)
				(type default)
			)
			(layer "F.SilkS")
		)
		(fp_line
			(start -0.508 -0.9398)
			(end -0.508 0.9398)
			(stroke
				(width 0.1524)
				(type default)
			)
			(layer "F.SilkS")
		)
		(fp_rect
			(start -0.508 0.9398)
			(end 0.508 -0.9398)
			(stroke
				(width 0)
				(type default)
			)
			(fill no)
			(layer "F.CrtYd")
		)
		(fp_rect
			(start -0.508 0.9398)
			(end 0.508 -0.9398)
			(stroke
				(width 0)
				(type default)
			)
			(fill no)
			(layer "F.Fab")
		)
		(pad "1" smd custom
			(at 0 -0.4445 180)
			(size 0.1397 0.1397)
			(layers "F.Cu" "F.Mask" "F.Paste")
			(net "BMC_I2C_SCL_BUF_9")
			(options
				(clearance outline)
				(anchor circle)
			)
			(primitives
				(gr_poly
					(pts
						(arc
							(start -0.1778 -0.2794)
							(mid -0.249642 -0.249642)
							(end -0.2794 -0.1778)
						)
						(arc
							(start -0.2794 0.1778)
							(mid -0.249642 0.249642)
							(end -0.1778 0.2794)
						)
						(arc
							(start 0.1778 0.2794)
							(mid 0.249642 0.249642)
							(end 0.2794 0.1778)
						)
						(arc
							(start 0.2794 -0.1778)
							(mid 0.249642 -0.249642)
							(end 0.1778 -0.2794)
						)
					)
					(width 0)
					(fill yes)
				)
			)
		)
		(pad "2" smd custom
			(at 0 0.4445 180)
			(size 0.1397 0.1397)
			(layers "F.Cu" "F.Mask" "F.Paste")
			(net "I2C8_SCL_R_SW_EU17")
			(options
				(clearance outline)
				(anchor circle)
			)
			(primitives
				(gr_poly
					(pts
						(arc
							(start -0.1778 -0.2794)
							(mid -0.249642 -0.249642)
							(end -0.2794 -0.1778)
						)
						(arc
							(start -0.2794 0.1778)
							(mid -0.249642 0.249642)
							(end -0.1778 0.2794)
						)
						(arc
							(start 0.1778 0.2794)
							(mid 0.249642 0.249642)
							(end 0.2794 0.1778)
						)
						(arc
							(start 0.2794 -0.1778)
							(mid 0.249642 -0.249642)
							(end 0.1778 -0.2794)
						)
					)
					(width 0)
					(fill yes)
				)
			)
		)
	)
)
